(kicad_pcb
	(version 20260206)
	(generator "pcbnew")
	(generator_version "10.0")
	(general
		(thickness 1.21888)
		(legacy_teardrops no)
	)
	(paper "A4")
	(title_block
		(title "timecard-v7 — TimeCard-DC-V7_EXP.PcbDoc")
		(comment 1 "Time Appliance Project (Time Card) / footprints 35-41 of 160")
	)
	(layers
		(0 "F.Cu" signal "TOP")
		(4 "In1.Cu" signal "SGND")
		(6 "In2.Cu" signal "IN1")
		(8 "In3.Cu" signal "IN2")
		(10 "In4.Cu" signal "SGND1")
		(2 "B.Cu" signal "BOTTOM")
		(9 "F.Adhes" user "F.Adhesive")
		(11 "B.Adhes" user "B.Adhesive")
		(13 "F.Paste" user "Top Paste")
		(15 "B.Paste" user "Bottom Paste")
		(5 "F.SilkS" user "Top Overlay")
		(7 "B.SilkS" user "Bottom Overlay")
		(1 "F.Mask" user "Top Solder")
		(3 "B.Mask" user "Bottom Solder")
		(17 "Dwgs.User" user "User.Drawings")
		(19 "Cmts.User" user "User.Comments")
		(21 "Eco1.User" user "User.Eco1")
		(23 "Eco2.User" user "User.Eco2")
		(25 "Edge.Cuts" user)
		(27 "Margin" user)
		(31 "F.CrtYd" user "Top Courtyard")
		(29 "B.CrtYd" user "Bottom Courtyard")
		(35 "F.Fab" user "Top Component Center")
		(33 "B.Fab" user "Bottom Component Center")
	)
	(footprint "SamacSys:SOP50P310X90-8N"
		(layer "F.Cu")
		(at 82.1261 95.6162 180)
		(property "Reference" "U8"
			(at 0.228605 2.026931 180)
			(unlocked yes)
			(layer "F.SilkS")
			(effects
				(font
					(size 0.762 0.762)
					(thickness 0.2286)
				)
			)
		)
		(property "Value" "NC7WV125K8X"
			(at 6.233115 2.911602 180)
			(unlocked yes)
			(layer "F.SilkS")
			(hide yes)
			(effects
				(font
					(size 1.524 1.524)
					(thickness 0.254)
				)
			)
		)
		(sheetname "USER_IO")
		(sheetfile "USER_IO.kicad_sch")
		(duplicate_pad_numbers_are_jumpers no)
		(fp_line
			(start 0.8 1)
			(end -0.8 1)
			(stroke
				(width 0.2)
				(type solid)
			)
			(layer "F.SilkS")
		)
		(fp_line
			(start 0.8 -1)
			(end 0.8 1)
			(stroke
				(width 0.2)
				(type solid)
			)
			(layer "F.SilkS")
		)
		(fp_line
			(start 0.8 -1)
			(end -0.8 -1)
			(stroke
				(width 0.2)
				(type solid)
			)
			(layer "F.SilkS")
		)
		(fp_line
			(start -0.8 -1)
			(end -0.8 1)
			(stroke
				(width 0.2)
				(type solid)
			)
			(layer "F.SilkS")
		)
		(fp_line
			(start -1.15 -1.25)
			(end -2 -1.25)
			(stroke
				(width 0.2)
				(type solid)
			)
			(layer "F.SilkS")
		)
		(pad "1" smd rect
			(at -1.575 -0.75 180)
			(size 0.85 0.3)
			(layers "F.Cu" "F.Mask" "F.Paste")
			(net "ANT1_IO_OUT")
		)
		(pad "2" smd rect
			(at -1.575 -0.25 180)
			(size 0.85 0.3)
			(layers "F.Cu" "F.Mask" "F.Paste")
			(net "ANT1_OUT")
		)
		(pad "3" smd rect
			(at -1.575 0.25 180)
			(size 0.85 0.3)
			(layers "F.Cu" "F.Mask" "F.Paste")
			(net "ANT1_IN")
		)
		(pad "4" smd rect
			(at -1.575 0.75 180)
			(size 0.85 0.3)
			(layers "F.Cu" "F.Mask" "F.Paste")
			(net "GND")
		)
		(pad "5" smd rect
			(at 1.575 0.75 180)
			(size 0.85 0.3)
			(layers "F.Cu" "F.Mask" "F.Paste")
			(net "NetR25_1")
		)
		(pad "6" smd rect
			(at 1.575 0.25 180)
			(size 0.85 0.3)
			(layers "F.Cu" "F.Mask" "F.Paste")
			(net "NetR25_1")
		)
		(pad "7" smd rect
			(at 1.575 -0.25 180)
			(size 0.85 0.3)
			(layers "F.Cu" "F.Mask" "F.Paste")
			(net "ANT1_IO_IN")
		)
		(pad "8" smd rect
			(at 1.575 -0.75 180)
			(size 0.85 0.3)
			(layers "F.Cu" "F.Mask" "F.Paste")
			(net "+3.3V")
		)
	)
	(footprint "Resistors:RESC1608X50N"
		(layer "F.Cu")
		(at 203.4405 114.0202 180)
		(property "Reference" "R2"
			(at 1.2144 0.710655 0)
			(unlocked yes)
			(layer "F.SilkS")
			(effects
				(font
					(size 0.762 0.762)
					(thickness 0.2286)
				)
				(justify left bottom)
			)
		)
		(property "Value" "ERJ-3EKF4702V"
			(at -6.3493 6.54541 0)
			(unlocked yes)
			(layer "F.SilkS")
			(hide yes)
			(effects
				(font
					(size 1.524 1.524)
					(thickness 0.254)
				)
				(justify left bottom)
			)
		)
		(sheetname "POWER")
		(sheetfile "POWER.kicad_sch")
		(duplicate_pad_numbers_are_jumpers no)
		(fp_line
			(start 0 -0.5)
			(end 0 0.5)
			(stroke
				(width 0.1524)
				(type solid)
			)
			(layer "F.SilkS")
		)
		(pad "1" smd rect
			(at -0.69 0 270)
			(size 1 0.72)
			(layers "F.Cu" "F.Mask" "F.Paste")
			(net "NetR2_1")
		)
		(pad "2" smd rect
			(at 0.69 0 270)
			(size 1 0.72)
			(layers "F.Cu" "F.Mask" "F.Paste")
			(net "+12V")
		)
	)
	(footprint "Vault:FP-MK212BG-MFG"
		(layer "F.Cu")
		(at 218.8761 60.5786 180)
		(property "Reference" "C34"
			(at 3.0214 -0.026921 0)
			(unlocked yes)
			(layer "F.SilkS")
			(effects
				(font
					(size 0.762 0.762)
					(thickness 0.2286)
				)
			)
		)
		(property "Value" "10uF"
			(at -3.267202 2.24704 90)
			(unlocked yes)
			(layer "F.SilkS")
			(hide yes)
			(effects
				(font
					(size 1.524 1.524)
					(thickness 0.254)
				)
			)
		)
		(sheetname "GPS_IMU_SENSORS")
		(sheetfile "GPS_IMU_SENSORS.kicad_sch")
		(duplicate_pad_numbers_are_jumpers no)
		(fp_line
			(start 0.125 0.725)
			(end -0.125 0.725)
			(stroke
				(width 0.2)
				(type solid)
			)
			(layer "F.SilkS")
		)
		(fp_line
			(start 0.125 -0.725)
			(end -0.125 -0.725)
			(stroke
				(width 0.2)
				(type solid)
			)
			(layer "F.SilkS")
		)
		(fp_line
			(start 1.6 0.825)
			(end -1.6 0.825)
			(stroke
				(width 0.2)
				(type solid)
			)
			(layer "F.CrtYd")
		)
		(fp_line
			(start 1.6 -0.825)
			(end 1.6 0.825)
			(stroke
				(width 0.2)
				(type solid)
			)
			(layer "F.CrtYd")
		)
		(fp_line
			(start 1.6 -0.825)
			(end -1.6 -0.825)
			(stroke
				(width 0.2)
				(type solid)
			)
			(layer "F.CrtYd")
		)
		(fp_line
			(start -1.6 -0.825)
			(end -1.6 0.825)
			(stroke
				(width 0.2)
				(type solid)
			)
			(layer "F.CrtYd")
		)
		(fp_line
			(start 1.6 0.825)
			(end -1.6 0.825)
			(stroke
				(width 0.2)
				(type solid)
			)
			(layer "F.Fab")
		)
		(fp_line
			(start 1.6 -0.825)
			(end 1.6 0.825)
			(stroke
				(width 0.2)
				(type solid)
			)
			(layer "F.Fab")
		)
		(fp_line
			(start 1.6 -0.825)
			(end -1.6 -0.825)
			(stroke
				(width 0.2)
				(type solid)
			)
			(layer "F.Fab")
		)
		(fp_line
			(start 0.5 0)
			(end -0.5 0)
			(stroke
				(width 0.1)
				(type solid)
			)
			(layer "F.Fab")
		)
		(fp_line
			(start 0 -0.5)
			(end 0 0.5)
			(stroke
				(width 0.1)
				(type solid)
			)
			(layer "F.Fab")
		)
		(fp_line
			(start -1.6 -0.825)
			(end -1.6 0.825)
			(stroke
				(width 0.2)
				(type solid)
			)
			(layer "F.Fab")
		)
		(fp_text user "${REFERENCE}"
			(at -0.00001 0.09602 180)
			(unlocked yes)
			(layer "F.Fab")
			(effects
				(font
					(face "Arial")
					(size 0.63 0.63)
					(thickness 0.1)
				)
				(justify left bottom)
			)
		)
		(pad "1" smd rect
			(at -1 0 180)
			(size 1 1.25)
			(layers "F.Cu" "F.Mask" "F.Paste")
			(net "+3.3V")
			(solder_mask_margin 0)
			(solder_paste_margin 0)
		)
		(pad "2" smd rect
			(at 1 0 180)
			(size 1 1.25)
			(layers "F.Cu" "F.Mask" "F.Paste")
			(net "GND")
			(solder_mask_margin 0)
			(solder_paste_margin 0)
		)
	)
	(footprint "IntegratedCircuits:SOIC127P600X175-8N"
		(layer "F.Cu")
		(at 207.5045 114.4012 90)
		(property "Reference" "U1"
			(at -4.215 -2.785055 90)
			(unlocked yes)
			(layer "F.SilkS")
			(effects
				(font
					(size 0.762 0.762)
					(thickness 0.2286)
				)
				(justify left bottom)
			)
		)
		(property "Value" "MP1482DS-LF"
			(at 0.75421 -0.6103 0)
			(unlocked yes)
			(layer "F.SilkS")
			(hide yes)
			(effects
				(font
					(size 1.524 1.524)
					(thickness 0.254)
				)
				(justify left bottom)
			)
		)
		(sheetname "POWER")
		(sheetfile "POWER.kicad_sch")
		(duplicate_pad_numbers_are_jumpers no)
		(fp_line
			(start -3.4 -2.5)
			(end 2 -2.5)
			(stroke
				(width 0.12)
				(type solid)
			)
			(layer "F.SilkS")
		)
		(fp_line
			(start -2 2.5)
			(end 2 2.5)
			(stroke
				(width 0.12)
				(type solid)
			)
			(layer "F.SilkS")
		)
		(pad "1" smd rect
			(at -2.475 -1.905 90)
			(size 1.97 0.57)
			(layers "F.Cu" "F.Mask" "F.Paste")
			(net "NetC4_1")
		)
		(pad "2" smd rect
			(at -2.475 -0.635 90)
			(size 1.97 0.57)
			(layers "F.Cu" "F.Mask" "F.Paste")
			(net "+12V")
		)
		(pad "3" smd rect
			(at -2.475 0.635 90)
			(size 1.97 0.57)
			(layers "F.Cu" "F.Mask" "F.Paste")
			(net "NetC4_2")
		)
		(pad "4" smd rect
			(at -2.475 1.905 90)
			(size 1.97 0.57)
			(layers "F.Cu" "F.Mask" "F.Paste")
			(net "GND")
		)
		(pad "5" smd rect
			(at 2.475 1.905 90)
			(size 1.97 0.57)
			(layers "F.Cu" "F.Mask" "F.Paste")
			(net "NetR4_2")
		)
		(pad "6" smd rect
			(at 2.475 0.635 90)
			(size 1.97 0.57)
			(layers "F.Cu" "F.Mask" "F.Paste")
			(net "NetC20_2")
		)
		(pad "7" smd rect
			(at 2.475 -0.635 90)
			(size 1.97 0.57)
			(layers "F.Cu" "F.Mask" "F.Paste")
			(net "NetR2_1")
		)
		(pad "8" smd rect
			(at 2.475 -1.905 90)
			(size 1.97 0.57)
			(layers "F.Cu" "F.Mask" "F.Paste")
			(net "NetC19_2")
		)
	)
	(footprint "Vault:CAPC1608X87X45ML20T05"
		(layer "F.Cu")
		(at 218.76876 58.67651)
		(property "Reference" "C36"
			(at -2.91406 -0.070979 0)
			(unlocked yes)
			(layer "F.SilkS")
			(effects
				(font
					(size 0.762 0.762)
					(thickness 0.2286)
				)
			)
		)
		(property "Value" "0.1uF"
			(at 2.09443 2.657602 0)
			(unlocked yes)
			(layer "F.SilkS")
			(hide yes)
			(effects
				(font
					(size 1.524 1.524)
					(thickness 0.254)
				)
			)
		)
		(sheetname "GPS_IMU_SENSORS")
		(sheetfile "GPS_IMU_SENSORS.kicad_sch")
		(duplicate_pad_numbers_are_jumpers no)
		(pad "1" smd rect
			(at -0.7 0 90)
			(size 1.1 1.05)
			(layers "F.Cu" "F.Mask" "F.Paste")
			(net "GND")
		)
		(pad "2" smd rect
			(at 0.7 0 90)
			(size 1.1 1.05)
			(layers "F.Cu" "F.Mask" "F.Paste")
			(net "+3.3V")
		)
	)
	(footprint "Vault:RESC3116X65X50ML20T20"
		(layer "F.Cu")
		(at 227.7261 121.2162 180)
		(property "Reference" "R44"
			(at 0.654005 -2.646148 180)
			(unlocked yes)
			(layer "F.SilkS")
			(effects
				(font
					(size 1.524 1.524)
					(thickness 0.254)
				)
			)
		)
		(property "Value" "DNI_0_5%_1206"
			(at 7.29942 3.318002 180)
			(unlocked yes)
			(layer "F.SilkS")
			(hide yes)
			(effects
				(font
					(size 1.524 1.524)
					(thickness 0.254)
				)
			)
		)
		(sheetname "POWER")
		(sheetfile "POWER.kicad_sch")
		(duplicate_pad_numbers_are_jumpers no)
		(fp_line
			(start 0.35 0.85)
			(end -0.35 0.85)
			(stroke
				(width 0.2)
				(type solid)
			)
			(layer "F.SilkS")
		)
		(fp_line
			(start 0.35 -0.85)
			(end -0.35 -0.85)
			(stroke
				(width 0.2)
				(type solid)
			)
			(layer "F.SilkS")
		)
		(pad "1" smd rect
			(at -1.475 0 270)
			(size 1.9 1.45)
			(layers "F.Cu" "F.Mask" "F.Paste")
			(net "NetD12_1")
		)
		(pad "2" smd rect
			(at 1.475 0 270)
			(size 1.9 1.45)
			(layers "F.Cu" "F.Mask" "F.Paste")
			(net "+12V")
		)
	)
	(footprint "Vault:FP-MK212BG-MFG"
		(layer "F.Cu")
		(at 227.6261 70.0786 180)
		(property "Reference" "C35"
			(at 3.0214 -0.026931 0)
			(unlocked yes)
			(layer "F.SilkS")
			(effects
				(font
					(size 0.762 0.762)
					(thickness 0.2286)
				)
			)
		)
		(property "Value" "10uF"
			(at -3.267202 2.24704 90)
			(unlocked yes)
			(layer "F.SilkS")
			(hide yes)
			(effects
				(font
					(size 1.524 1.524)
					(thickness 0.254)
				)
			)
		)
		(sheetname "GPS_IMU_SENSORS")
		(sheetfile "GPS_IMU_SENSORS.kicad_sch")
		(duplicate_pad_numbers_are_jumpers no)
		(fp_line
			(start 0.125 0.725)
			(end -0.125 0.725)
			(stroke
				(width 0.2)
				(type solid)
			)
			(layer "F.SilkS")
		)
		(fp_line
			(start 0.125 -0.725)
			(end -0.125 -0.725)
			(stroke
				(width 0.2)
				(type solid)
			)
			(layer "F.SilkS")
		)
		(fp_line
			(start 1.6 0.825)
			(end -1.6 0.825)
			(stroke
				(width 0.2)
				(type solid)
			)
			(layer "F.CrtYd")
		)
		(fp_line
			(start 1.6 -0.825)
			(end 1.6 0.825)
			(stroke
				(width 0.2)
				(type solid)
			)
			(layer "F.CrtYd")
		)
		(fp_line
			(start 1.6 -0.825)
			(end -1.6 -0.825)
			(stroke
				(width 0.2)
				(type solid)
			)
			(layer "F.CrtYd")
		)
		(fp_line
			(start -1.6 -0.825)
			(end -1.6 0.825)
			(stroke
				(width 0.2)
				(type solid)
			)
			(layer "F.CrtYd")
		)
		(fp_line
			(start 1.6 0.825)
			(end -1.6 0.825)
			(stroke
				(width 0.2)
				(type solid)
			)
			(layer "F.Fab")
		)
		(fp_line
			(start 1.6 -0.825)
			(end 1.6 0.825)
			(stroke
				(width 0.2)
				(type solid)
			)
			(layer "F.Fab")
		)
		(fp_line
			(start 1.6 -0.825)
			(end -1.6 -0.825)
			(stroke
				(width 0.2)
				(type solid)
			)
			(layer "F.Fab")
		)
		(fp_line
			(start 0.5 0)
			(end -0.5 0)
			(stroke
				(width 0.1)
				(type solid)
			)
			(layer "F.Fab")
		)
		(fp_line
			(start 0 -0.5)
			(end 0 0.5)
			(stroke
				(width 0.1)
				(type solid)
			)
			(layer "F.Fab")
		)
		(fp_line
			(start -1.6 -0.825)
			(end -1.6 0.825)
			(stroke
				(width 0.2)
				(type solid)
			)
			(layer "F.Fab")
		)
		(fp_text user "${REFERENCE}"
			(at -0.00001 0.09602 180)
			(unlocked yes)
			(layer "F.Fab")
			(effects
				(font
					(face "Arial")
					(size 0.63 0.63)
					(thickness 0.1)
				)
				(justify left bottom)
			)
		)
		(pad "1" smd rect
			(at -1 0 180)
			(size 1 1.25)
			(layers "F.Cu" "F.Mask" "F.Paste")
			(net "+5.0V")
			(solder_mask_margin 0)
			(solder_paste_margin 0)
		)
		(pad "2" smd rect
			(at 1 0 180)
			(size 1 1.25)
			(layers "F.Cu" "F.Mask" "F.Paste")
			(net "GND")
			(solder_mask_margin 0)
			(solder_paste_margin 0)
		)
	)
)
